# BARRELEYE-G2-SXM2 RISER BOARD-EVT-X00-BOM-X01-20171102_Final.xls.xlsx — TBD AVL Qual (bom)
| NOTES: |  |  |  |  |  |  |
| The following items are alternates to the items listed in the Critical Components Qual tab. |  |  |  |  |  |  |
| These components will be included on near future, non-customer builds for validation and approval by both Customer and the ODM. |  |  |  |  |  |  |
| Item Description | ODM P/N | Customer PN | Vendor | Vendor PN | Build ?? | Estimated Completion Date |
| SATA connectors (black) |  |  |  |  |  |  |
| -  Alternate |  |  |  |  |  |  |
| SATA connectors (blue) |  |  |  |  |  |  |
| -  Alternate |  |  |  |  |  |  |
| PCIe retention |  |  |  |  |  |  |
| -  Alternate |  |  |  |  |  |  |
| RTC XTAL |  |  |  |  |  |  |
| -  Alternate |  |  |  |  |  |  |
| XTAL |  |  |  |  |  |  |
| -  Alternate |  |  |  |  |  |  |
